# S9S_MB_2U (Grand Teton) — schematic netlist excerpt (pin names and nets, part order shuffled) for the footprints in the layout excerpt that follows; sources: Cadence DE-HDL packaged netlist, KiCad conversion of 03242023_DA0F0TMBIJ0_F0T_Motherboard_J_brd_V01_OCP.brd

D142  Q_LED  IC  pkg SMLF  page 255 : A = LED_P12V_AUX_R1 ; C = GND
C275  Q_CAP  22UF 4V 20% X6S  pkg C0402  page 77 : A = PVCCIN_CPU1 ; B = GND

(kicad_pcb
	(version 20260206)
	(generator "pcbnew")
	(generator_version "10.0")
	(general
		(thickness 1.6)
		(legacy_teardrops no)
	)
	(paper "A4")
	(title_block
		(title "03242023_DA0F0TMBIJ0_F0T_Motherboard_J_brd_V01_OCP.brd")
		(comment 1 "Grand Teton / footprints 790-791 of 6105")
	)
	(layers
		(0 "F.Cu" signal "TOP")
		(4 "In1.Cu" signal "GND")
		(6 "In2.Cu" signal "IN1")
		(8 "In3.Cu" signal "GND1")
		(10 "In4.Cu" signal "IN2")
		(12 "In5.Cu" signal "GND2")
		(14 "In6.Cu" signal "IN3")
		(16 "In7.Cu" signal "GND3")
		(18 "In8.Cu" signal "VCC")
		(20 "In9.Cu" signal "VCC1")
		(22 "In10.Cu" signal "GND4")
		(24 "In11.Cu" signal "IN4")
		(26 "In12.Cu" signal "GND5")
		(28 "In13.Cu" signal "IN5")
		(30 "In14.Cu" signal "GND6")
		(32 "In15.Cu" signal "IN6")
		(34 "In16.Cu" signal "GND7")
		(2 "B.Cu" signal "BOTTOM")
		(9 "F.Adhes" user "F.Adhesive")
		(11 "B.Adhes" user "B.Adhesive")
		(13 "F.Paste" user "Package Geometry/Pastemask Top")
		(15 "B.Paste" user "Package Geometry/Pastemask Bottom")
		(5 "F.SilkS" user "Ref Des/Silkscreen Top")
		(7 "B.SilkS" user "Ref Des/Silkscreen Bottom")
		(1 "F.Mask" user "Board Geometry/Soldermask Top")
		(3 "B.Mask" user "Board Geometry/Soldermask Bottom")
		(17 "Dwgs.User" user "User.Drawings")
		(19 "Cmts.User" user "User.Comments")
		(21 "Eco1.User" user "User.Eco1")
		(23 "Eco2.User" user "User.Eco2")
		(25 "Edge.Cuts" user "Board Geometry/Outline")
		(27 "Margin" user)
		(31 "F.CrtYd" user "Package Geometry/Place Bound Top")
		(29 "B.CrtYd" user "Package Geometry/Place Bound Bottom")
		(35 "F.Fab" user "Ref Des/Assembly Top")
		(33 "B.Fab" user "Ref Des/Assembly Bottom")
	)
	(footprint ""
		(layer "F.Cu")
		(at 107.2769 -252.956568 -90)
		(property "Reference" "C275"
			(at 0 0 270)
			(layer "F.SilkS")
			(hide yes)
			(effects
				(font
					(size 1.27 1.27)
				)
			)
		)
		(property "Value" ""
			(at 0 0 270)
			(layer "F.Fab")
			(effects
				(font
					(size 1.27 1.27)
				)
			)
		)
		(duplicate_pad_numbers_are_jumpers no)
		(fp_line
			(start -0.7874 0.4064)
			(end -0.7874 -0.4064)
			(stroke
				(width 0.1524)
				(type default)
			)
			(layer "F.SilkS")
		)
		(fp_line
			(start 0.7874 0.4064)
			(end -0.7874 0.4064)
			(stroke
				(width 0.1524)
				(type default)
			)
			(layer "F.SilkS")
		)
		(fp_line
			(start -0.7874 -0.4064)
			(end 0.7874 -0.4064)
			(stroke
				(width 0.1524)
				(type default)
			)
			(layer "F.SilkS")
		)
		(fp_line
			(start 0.7874 -0.4064)
			(end 0.7874 0.4064)
			(stroke
				(width 0.1524)
				(type default)
			)
			(layer "F.SilkS")
		)
		(fp_line
			(start -0.67945 0.3048)
			(end -0.67945 -0.305054)
			(stroke
				(width 0.1)
				(type default)
			)
			(layer "F.Fab")
		)
		(fp_line
			(start -0.12065 0.3048)
			(end -0.67945 0.3048)
			(stroke
				(width 0.1)
				(type default)
			)
			(layer "F.Fab")
		)
		(fp_line
			(start 0.120396 0.3048)
			(end 0.120396 0.2794)
			(stroke
				(width 0.1)
				(type default)
			)
			(layer "F.Fab")
		)
		(fp_line
			(start 0.67945 0.3048)
			(end 0.120396 0.3048)
			(stroke
				(width 0.1)
				(type default)
			)
			(layer "F.Fab")
		)
		(fp_line
			(start -0.12065 0.2794)
			(end -0.12065 0.3048)
			(stroke
				(width 0.1)
				(type default)
			)
			(layer "F.Fab")
		)
		(fp_line
			(start 0.120396 0.2794)
			(end -0.12065 0.2794)
			(stroke
				(width 0.1)
				(type default)
			)
			(layer "F.Fab")
		)
		(fp_line
			(start -0.12065 -0.2794)
			(end 0.12065 -0.2794)
			(stroke
				(width 0.1)
				(type default)
			)
			(layer "F.Fab")
		)
		(fp_line
			(start 0.12065 -0.2794)
			(end 0.12065 -0.3048)
			(stroke
				(width 0.1)
				(type default)
			)
			(layer "F.Fab")
		)
		(fp_line
			(start 0.12065 -0.3048)
			(end 0.67945 -0.3048)
			(stroke
				(width 0.1)
				(type default)
			)
			(layer "F.Fab")
		)
		(fp_line
			(start 0.67945 -0.3048)
			(end 0.67945 0.3048)
			(stroke
				(width 0.1)
				(type default)
			)
			(layer "F.Fab")
		)
		(fp_line
			(start -0.67945 -0.305054)
			(end -0.12065 -0.305054)
			(stroke
				(width 0.1)
				(type default)
			)
			(layer "F.Fab")
		)
		(fp_line
			(start -0.12065 -0.305054)
			(end -0.12065 -0.2794)
			(stroke
				(width 0.1)
				(type default)
			)
			(layer "F.Fab")
		)
		(pad "1" smd circle
			(at -0.40005 0 270)
			(size 0 0)
			(layers "F.Cu" "F.Mask" "F.Paste")
			(net "PVCCIN_CPU1")
		)
		(pad "2" smd circle
			(at 0.40005 0 270)
			(size 0 0)
			(layers "F.Cu" "F.Mask" "F.Paste")
			(net "GND")
		)
	)
	(footprint ""
		(layer "F.Cu")
		(at 368.7572 -71.42226)
		(property "Reference" "D142"
			(at -5.7912 -0.94107 0)
			(unlocked yes)
			(layer "F.SilkS")
			(effects
				(font
					(size 0.7874 0.5842)
					(thickness 0.1524)
				)
				(justify left)
			)
		)
		(property "Value" ""
			(at 0 0 0)
			(layer "F.Fab")
			(effects
				(font
					(size 1.27 1.27)
				)
			)
		)
		(duplicate_pad_numbers_are_jumpers no)
		(fp_line
			(start -0.90678 0.4826)
			(end -0.90678 -0.4699)
			(stroke
				(width 0.1524)
				(type default)
			)
			(layer "F.SilkS")
		)
		(fp_line
			(start -0.89408 -0.4826)
			(end 0.90678 -0.4826)
			(stroke
				(width 0.1524)
				(type default)
			)
			(layer "F.SilkS")
		)
		(fp_line
			(start -0.79248 -0.4826)
			(end 1.03378 -0.4826)
			(stroke
				(width 0.1524)
				(type default)
			)
			(layer "F.SilkS")
		)
		(fp_line
			(start -0.64008 -0.4826)
			(end 1.16078 -0.4826)
			(stroke
				(width 0.1524)
				(type default)
			)
			(layer "F.SilkS")
		)
		(fp_line
			(start 0.90678 -0.4826)
			(end 0.90678 0.4826)
			(stroke
				(width 0.1524)
				(type default)
			)
			(layer "F.SilkS")
		)
		(fp_line
			(start 0.90678 0.4826)
			(end -0.90678 0.4826)
			(stroke
				(width 0.1524)
				(type default)
			)
			(layer "F.SilkS")
		)
		(fp_line
			(start 1.03378 -0.4826)
			(end 1.03378 0.4826)
			(stroke
				(width 0.1524)
				(type default)
			)
			(layer "F.SilkS")
		)
		(fp_line
			(start 1.03378 0.4826)
			(end -0.79248 0.4826)
			(stroke
				(width 0.1524)
				(type default)
			)
			(layer "F.SilkS")
		)
		(fp_line
			(start 1.16078 -0.4826)
			(end 1.16078 0.4826)
			(stroke
				(width 0.1524)
				(type default)
			)
			(layer "F.SilkS")
		)
		(fp_line
			(start 1.16078 0.4826)
			(end -0.64008 0.4826)
			(stroke
				(width 0.1524)
				(type default)
			)
			(layer "F.SilkS")
		)
		(fp_line
			(start -0.499872 -0.249936)
			(end 0.499872 -0.249936)
			(stroke
				(width 0.1)
				(type default)
			)
			(layer "F.Fab")
		)
		(fp_line
			(start -0.499872 0.249936)
			(end -0.499872 -0.249936)
			(stroke
				(width 0.1)
				(type default)
			)
			(layer "F.Fab")
		)
		(fp_line
			(start 0.499872 -0.249936)
			(end 0.499872 0.249936)
			(stroke
				(width 0.1)
				(type default)
			)
			(layer "F.Fab")
		)
		(fp_line
			(start 0.499872 0.249936)
			(end -0.499872 0.249936)
			(stroke
				(width 0.1)
				(type default)
			)
			(layer "F.Fab")
		)
		(pad "A" smd rect
			(at -0.47498 0)
			(size 0.6096 0.7112)
			(layers "F.Cu" "F.Mask" "F.Paste")
			(net "LED_P12V_AUX_R1")
		)
		(pad "C" smd rect
			(at 0.47498 0)
			(size 0.6096 0.7112)
			(layers "F.Cu" "F.Mask" "F.Paste")
			(net "GND")
		)
	)
)
